(kicad_pcb
	(version 20260206)
	(generator "pcbnew")
	(generator_version "10.0")
	(general
		(thickness 1.6)
		(legacy_teardrops no)
	)
	(paper "A4")
	(title_block
		(title "fcb — 12433-1M.1206WZS1330.brd")
		(comment 1 "Open Vault / Knox (Wiwynn) / footprints 46-50 of 495")
	)
	(layers
		(0 "F.Cu" signal "TOP")
		(4 "In1.Cu" signal "L2GND")
		(6 "In2.Cu" signal "L3VCC")
		(2 "B.Cu" signal "BOTTOM")
		(9 "F.Adhes" user "F.Adhesive")
		(11 "B.Adhes" user "B.Adhesive")
		(13 "F.Paste" user "Package Geometry/Pastemask Top")
		(15 "B.Paste" user "Package Geometry/Pastemask Bottom")
		(5 "F.SilkS" user "Ref Des/Silkscreen Top")
		(7 "B.SilkS" user "Ref Des/Silkscreen Bottom")
		(1 "F.Mask" user "Board Geometry/Soldermask Top")
		(3 "B.Mask" user "Board Geometry/Soldermask Bottom")
		(17 "Dwgs.User" user "User.Drawings")
		(19 "Cmts.User" user "User.Comments")
		(21 "Eco1.User" user "User.Eco1")
		(23 "Eco2.User" user "User.Eco2")
		(25 "Edge.Cuts" user "Board Geometry/Outline")
		(27 "Margin" user)
		(31 "F.CrtYd" user "Package Geometry/Place Bound Top")
		(29 "B.CrtYd" user "Package Geometry/Place Bound Bottom")
		(35 "F.Fab" user "Ref Des/Assembly Top")
		(33 "B.Fab" user "Ref Des/Assembly Bottom")
	)
	(footprint ""
		(layer "F.Cu")
		(at 38.354 -378.333 180)
		(property "Reference" "PR28"
			(at 0 0 180)
			(layer "F.SilkS")
			(hide yes)
			(effects
				(font
					(size 1.27 1.27)
				)
			)
		)
		(property "Value" "10R2F-L-GP"
			(at 0.064008 -3.993896 180)
			(unlocked yes)
			(layer "F.Fab")
			(hide yes)
			(effects
				(font
					(size 1.016 1.016)
					(thickness 0.1524)
				)
			)
		)
		(property "Device Type" "R402H14"
			(at 0.064008 -5.517896 180)
			(unlocked yes)
			(layer "F.Fab")
			(hide yes)
			(effects
				(font
					(size 1.016 1.016)
					(thickness 0.1524)
				)
			)
		)
		(duplicate_pad_numbers_are_jumpers no)
		(fp_line
			(start 0.508 -0.9398)
			(end -0.508 -0.9398)
			(stroke
				(width 0.1524)
				(type default)
			)
			(layer "F.SilkS")
		)
		(fp_line
			(start -0.508 -0.9398)
			(end -0.508 0.9398)
			(stroke
				(width 0.1524)
				(type default)
			)
			(layer "F.SilkS")
		)
		(fp_rect
			(start -0.508 0.9398)
			(end 0.508 -0.9398)
			(stroke
				(width 0)
				(type default)
			)
			(fill no)
			(layer "F.CrtYd")
		)
		(fp_rect
			(start -0.508 0.9398)
			(end 0.508 -0.9398)
			(stroke
				(width 0)
				(type default)
			)
			(fill no)
			(layer "F.Fab")
		)
		(pad "1" smd custom
			(at 0 -0.4445 180)
			(size 0.1397 0.1397)
			(layers "F.Cu" "F.Mask" "F.Paste")
			(net "ADM1276_GATE")
			(options
				(clearance outline)
				(anchor circle)
			)
			(primitives
				(gr_poly
					(pts
						(arc
							(start -0.1778 -0.2794)
							(mid -0.249642 -0.249642)
							(end -0.2794 -0.1778)
						)
						(arc
							(start -0.2794 0.1778)
							(mid -0.249642 0.249642)
							(end -0.1778 0.2794)
						)
						(arc
							(start 0.1778 0.2794)
							(mid 0.249642 0.249642)
							(end 0.2794 0.1778)
						)
						(arc
							(start 0.2794 -0.1778)
							(mid 0.249642 -0.249642)
							(end 0.1778 -0.2794)
						)
					)
					(width 0)
					(fill yes)
				)
			)
		)
		(pad "2" smd custom
			(at 0 0.4445 180)
			(size 0.1397 0.1397)
			(layers "F.Cu" "F.Mask" "F.Paste")
			(net "ADM1276_GATE_DRV3")
			(options
				(clearance outline)
				(anchor circle)
			)
			(primitives
				(gr_poly
					(pts
						(arc
							(start -0.1778 -0.2794)
							(mid -0.249642 -0.249642)
							(end -0.2794 -0.1778)
						)
						(arc
							(start -0.2794 0.1778)
							(mid -0.249642 0.249642)
							(end -0.1778 0.2794)
						)
						(arc
							(start 0.1778 0.2794)
							(mid 0.249642 0.249642)
							(end 0.2794 0.1778)
						)
						(arc
							(start 0.2794 -0.1778)
							(mid 0.249642 -0.249642)
							(end 0.1778 -0.2794)
						)
					)
					(width 0)
					(fill yes)
				)
			)
		)
	)
	(footprint ""
		(layer "F.Cu")
		(at 32.749998 -451.820026)
		(property "Reference" "CN8"
			(at 0 0 0)
			(layer "F.SilkS")
			(hide yes)
			(effects
				(font
					(size 1.27 1.27)
				)
			)
		)
		(property "Value" "JWT-CON3-S11-GP"
			(at 5.715 1.1684 0)
			(unlocked yes)
			(layer "F.Fab")
			(hide yes)
			(effects
				(font
					(size 1.016 1.016)
					(thickness 0.1524)
				)
			)
		)
		(property "Device Type" "A2541WV0-1QX3PA-6T"
			(at 5.715 -0.3556 0)
			(unlocked yes)
			(layer "F.Fab")
			(hide yes)
			(effects
				(font
					(size 1.016 1.016)
					(thickness 0.1524)
				)
			)
		)
		(duplicate_pad_numbers_are_jumpers no)
		(fp_line
			(start -4.190746 -1.651)
			(end -2.920746 -1.651)
			(stroke
				(width 0.4064)
				(type default)
			)
			(layer "F.SilkS")
		)
		(fp_line
			(start -4.190746 -0.381)
			(end -4.190746 -1.651)
			(stroke
				(width 0.4064)
				(type default)
			)
			(layer "F.SilkS")
		)
		(fp_line
			(start -4.064 -1.524)
			(end -4.064 1.524)
			(stroke
				(width 0.1524)
				(type default)
			)
			(layer "F.SilkS")
		)
		(fp_line
			(start -4.064 1.524)
			(end 4.064 1.524)
			(stroke
				(width 0.1524)
				(type default)
			)
			(layer "F.SilkS")
		)
		(fp_line
			(start 4.064 -1.524)
			(end -4.064 -1.524)
			(stroke
				(width 0.1524)
				(type default)
			)
			(layer "F.SilkS")
		)
		(fp_line
			(start 4.064 1.524)
			(end 4.064 -1.524)
			(stroke
				(width 0.1524)
				(type default)
			)
			(layer "F.SilkS")
		)
		(fp_circle
			(center -2.54 0)
			(end -1.4732 0)
			(stroke
				(width 0.3048)
				(type default)
			)
			(fill no)
			(layer "F.SilkS")
		)
		(fp_circle
			(center 0 0)
			(end 1.0668 0)
			(stroke
				(width 0.3048)
				(type default)
			)
			(fill no)
			(layer "F.SilkS")
		)
		(fp_circle
			(center 2.54 0)
			(end 3.6068 0)
			(stroke
				(width 0.3048)
				(type default)
			)
			(fill no)
			(layer "F.SilkS")
		)
		(fp_rect
			(start -3.81 1.27)
			(end 3.81 -1.27)
			(stroke
				(width 0)
				(type default)
			)
			(fill no)
			(layer "F.CrtYd")
		)
		(fp_poly
			(pts
				(xy -4.318 1.778) (xy -4.318 -1.778) (xy 4.318 -1.778) (xy 4.318 -1.27) (xy -3.81 -1.27) (xy -3.81 1.27)
				(xy 3.81 1.27) (xy 3.81 -1.2573) (xy 4.318 -1.2573) (xy 4.318 1.778)
			)
			(stroke
				(width 0)
				(type default)
			)
			(fill no)
			(layer "F.CrtYd")
		)
		(fp_rect
			(start -4.318 1.778)
			(end 4.318 -1.778)
			(stroke
				(width 0)
				(type default)
			)
			(fill no)
			(layer "F.Fab")
		)
		(pad "1" thru_hole circle
			(at -2.54 0)
			(size 1.4224 1.4224)
			(drill 1.016)
			(layers "*.Cu" "*.Mask")
			(remove_unused_layers no)
			(net "Net_3")
			(clearance 0.1524)
			(thermal_gap 0.1524)
		)
		(pad "2" thru_hole circle
			(at 0 0)
			(size 1.4224 1.4224)
			(drill 1.016)
			(layers "*.Cu" "*.Mask")
			(remove_unused_layers no)
			(net "Net_2")
			(clearance 0.1524)
			(thermal_gap 0.1524)
		)
		(pad "3" thru_hole circle
			(at 2.54 0)
			(size 1.4224 1.4224)
			(drill 1.016)
			(layers "*.Cu" "*.Mask")
			(remove_unused_layers no)
			(net "Net_1")
			(clearance 0.1524)
			(thermal_gap 0.1524)
		)
	)
	(footprint ""
		(layer "F.Cu")
		(at 34.3916 -184.4802)
		(property "Reference" "PQ10"
			(at 0 0 0)
			(layer "F.SilkS")
			(hide yes)
			(effects
				(font
					(size 1.27 1.27)
				)
			)
		)
		(property "Value" "PMBS3904-1-GP"
			(at 0 -9.0932 0)
			(unlocked yes)
			(layer "F.Fab")
			(hide yes)
			(effects
				(font
					(size 1.016 1.016)
					(thickness 0.1524)
				)
			)
		)
		(property "Device Type" "SOT-23-10H44"
			(at 0 -10.6172 0)
			(unlocked yes)
			(layer "F.Fab")
			(hide yes)
			(effects
				(font
					(size 1.016 1.016)
					(thickness 0.1524)
				)
			)
		)
		(duplicate_pad_numbers_are_jumpers no)
		(fp_line
			(start -1.7526 1.8796)
			(end -1.7526 0.9906)
			(stroke
				(width 0.3302)
				(type default)
			)
			(layer "F.SilkS")
		)
		(fp_line
			(start -1.651 -1.778)
			(end -1.651 1.778)
			(stroke
				(width 0.1524)
				(type default)
			)
			(layer "F.SilkS")
		)
		(fp_line
			(start -1.651 1.778)
			(end 1.651 1.778)
			(stroke
				(width 0.1524)
				(type default)
			)
			(layer "F.SilkS")
		)
		(fp_line
			(start -1.279398 2.152142)
			(end -0.9906 1.86309)
			(stroke
				(width 0.0127)
				(type default)
			)
			(layer "F.SilkS")
		)
		(fp_line
			(start -1.279144 2.15265)
			(end -0.701294 2.15265)
			(stroke
				(width 0.0127)
				(type default)
			)
			(layer "F.SilkS")
		)
		(fp_line
			(start -1.260856 2.1336)
			(end -0.720344 2.1336)
			(stroke
				(width 0.0127)
				(type default)
			)
			(layer "F.SilkS")
		)
		(fp_line
			(start -1.251458 2.124202)
			(end -0.729996 2.124202)
			(stroke
				(width 0.0127)
				(type default)
			)
			(layer "F.SilkS")
		)
		(fp_line
			(start -1.241806 2.11455)
			(end -0.739394 2.11455)
			(stroke
				(width 0.0127)
				(type default)
			)
			(layer "F.SilkS")
		)
		(fp_line
			(start -1.232408 2.105152)
			(end -0.749046 2.105152)
			(stroke
				(width 0.0127)
				(type default)
			)
			(layer "F.SilkS")
		)
		(fp_line
			(start -1.222756 2.0955)
			(end -0.758444 2.0955)
			(stroke
				(width 0.0127)
				(type default)
			)
			(layer "F.SilkS")
		)
		(fp_line
			(start -1.213358 2.086102)
			(end -0.768096 2.086102)
			(stroke
				(width 0.0127)
				(type default)
			)
			(layer "F.SilkS")
		)
		(fp_line
			(start -1.203706 2.07645)
			(end -0.777494 2.07645)
			(stroke
				(width 0.0127)
				(type default)
			)
			(layer "F.SilkS")
		)
		(fp_line
			(start -1.194308 2.067052)
			(end -0.787146 2.067052)
			(stroke
				(width 0.0127)
				(type default)
			)
			(layer "F.SilkS")
		)
		(fp_line
			(start -1.184656 2.0574)
			(end -0.796544 2.0574)
			(stroke
				(width 0.0127)
				(type default)
			)
			(layer "F.SilkS")
		)
		(fp_line
			(start -1.175258 2.048002)
			(end -0.806196 2.048002)
			(stroke
				(width 0.0127)
				(type default)
			)
			(layer "F.SilkS")
		)
		(fp_line
			(start -1.165606 2.03835)
			(end -0.815594 2.03835)
			(stroke
				(width 0.0127)
				(type default)
			)
			(layer "F.SilkS")
		)
		(fp_line
			(start -1.156208 2.028952)
			(end -0.825246 2.028952)
			(stroke
				(width 0.0127)
				(type default)
			)
			(layer "F.SilkS")
		)
		(fp_line
			(start -1.146556 2.0193)
			(end -0.834644 2.0193)
			(stroke
				(width 0.0127)
				(type default)
			)
			(layer "F.SilkS")
		)
		(fp_line
			(start -1.137158 2.009902)
			(end -0.844296 2.009902)
			(stroke
				(width 0.0127)
				(type default)
			)
			(layer "F.SilkS")
		)
		(fp_line
			(start -1.127506 2.00025)
			(end -0.853694 2.00025)
			(stroke
				(width 0.0127)
				(type default)
			)
			(layer "F.SilkS")
		)
		(fp_line
			(start -1.118108 1.990852)
			(end -0.863346 1.990852)
			(stroke
				(width 0.0127)
				(type default)
			)
			(layer "F.SilkS")
		)
		(fp_line
			(start -1.108456 1.9812)
			(end -0.872744 1.9812)
			(stroke
				(width 0.0127)
				(type default)
			)
			(layer "F.SilkS")
		)
		(fp_line
			(start -1.099058 1.971802)
			(end -0.882396 1.971802)
			(stroke
				(width 0.0127)
				(type default)
			)
			(layer "F.SilkS")
		)
		(fp_line
			(start -1.089406 1.96215)
			(end -0.891794 1.96215)
			(stroke
				(width 0.0127)
				(type default)
			)
			(layer "F.SilkS")
		)
		(fp_line
			(start -1.080008 1.952752)
			(end -0.901446 1.952752)
			(stroke
				(width 0.0127)
				(type default)
			)
			(layer "F.SilkS")
		)
		(fp_line
			(start -1.070356 1.9431)
			(end -0.910844 1.9431)
			(stroke
				(width 0.0127)
				(type default)
			)
			(layer "F.SilkS")
		)
		(fp_line
			(start -1.060958 1.933702)
			(end -0.920496 1.933702)
			(stroke
				(width 0.0127)
				(type default)
			)
			(layer "F.SilkS")
		)
		(fp_line
			(start -1.051306 1.92405)
			(end -0.929894 1.92405)
			(stroke
				(width 0.0127)
				(type default)
			)
			(layer "F.SilkS")
		)
		(fp_line
			(start -1.041908 1.914652)
			(end -0.939546 1.914652)
			(stroke
				(width 0.0127)
				(type default)
			)
			(layer "F.SilkS")
		)
		(fp_line
			(start -1.032256 1.905)
			(end -0.948944 1.905)
			(stroke
				(width 0.0127)
				(type default)
			)
			(layer "F.SilkS")
		)
		(fp_line
			(start -1.022858 1.895602)
			(end -0.958596 1.895602)
			(stroke
				(width 0.0127)
				(type default)
			)
			(layer "F.SilkS")
		)
		(fp_line
			(start -1.013206 1.88595)
			(end -0.967994 1.88595)
			(stroke
				(width 0.0127)
				(type default)
			)
			(layer "F.SilkS")
		)
		(fp_line
			(start -1.003808 1.876552)
			(end -0.977646 1.876552)
			(stroke
				(width 0.0127)
				(type default)
			)
			(layer "F.SilkS")
		)
		(fp_line
			(start -0.994156 1.8669)
			(end -0.987044 1.8669)
			(stroke
				(width 0.0127)
				(type default)
			)
			(layer "F.SilkS")
		)
		(fp_line
			(start -0.9906 1.86309)
			(end -0.701294 2.15265)
			(stroke
				(width 0.0127)
				(type default)
			)
			(layer "F.SilkS")
		)
		(fp_line
			(start -0.719074 2.145538)
			(end -1.265936 2.14122)
			(stroke
				(width 0.0127)
				(type default)
			)
			(layer "F.SilkS")
		)
		(fp_line
			(start -0.71628 2.15265)
			(end -1.26492 2.15265)
			(stroke
				(width 0.0127)
				(type default)
			)
			(layer "F.SilkS")
		)
		(fp_line
			(start -0.635 1.8796)
			(end -1.7526 1.8796)
			(stroke
				(width 0.3302)
				(type default)
			)
			(layer "F.SilkS")
		)
		(fp_line
			(start 1.651 -1.778)
			(end -1.651 -1.778)
			(stroke
				(width 0.1524)
				(type default)
			)
			(layer "F.SilkS")
		)
		(fp_line
			(start 1.651 1.778)
			(end 1.651 -1.778)
			(stroke
				(width 0.1524)
				(type default)
			)
			(layer "F.SilkS")
		)
		(fp_poly
			(pts
				(xy -1.285748 2.159) (xy -1.285748 1.8796) (xy -1.778 1.8796) (xy -1.778 -1.8796) (xy 1.778 -1.8796)
				(xy 1.778 1.8796) (xy -0.694944 1.8796) (xy -0.694944 2.159)
			)
			(stroke
				(width 0)
				(type default)
			)
			(fill no)
			(layer "F.CrtYd")
		)
		(fp_poly
			(pts
				(xy -1.285748 2.159) (xy -1.285748 1.8796) (xy -1.778 1.8796) (xy -1.778 -1.8796) (xy 1.778 -1.8796)
				(xy 1.778 1.8796) (xy -0.694944 1.8796) (xy -0.694944 2.159)
			)
			(stroke
				(width 0)
				(type default)
			)
			(fill no)
			(layer "F.Fab")
		)
		(pad "1" smd rect
			(at -0.98425 0.9525)
			(size 0.762 1.143)
			(layers "F.Cu" "F.Mask" "F.Paste")
			(net "P3V3_AUX_BJT_B")
		)
		(pad "2" smd rect
			(at 0.98425 0.9525)
			(size 0.762 1.143)
			(layers "F.Cu" "F.Mask" "F.Paste")
			(net "P3V3_AUX")
		)
		(pad "3" smd rect
			(at 0 -0.9525)
			(size 0.762 1.143)
			(layers "F.Cu" "F.Mask" "F.Paste")
			(net "P12V_AUX")
		)
	)
	(footprint ""
		(layer "F.Cu")
		(at 32.7406 -149.071584 180)
		(property "Reference" "R36"
			(at 0 0 180)
			(layer "F.SilkS")
			(hide yes)
			(effects
				(font
					(size 1.27 1.27)
				)
			)
		)
		(property "Value" "110KR2F-L-GP"
			(at 0.064008 -3.993896 180)
			(unlocked yes)
			(layer "F.Fab")
			(hide yes)
			(effects
				(font
					(size 1.016 1.016)
					(thickness 0.1524)
				)
			)
		)
		(property "Device Type" "R402H16"
			(at 0.064008 -5.517896 180)
			(unlocked yes)
			(layer "F.Fab")
			(hide yes)
			(effects
				(font
					(size 1.016 1.016)
					(thickness 0.1524)
				)
			)
		)
		(duplicate_pad_numbers_are_jumpers no)
		(fp_line
			(start 0.508 -0.9398)
			(end -0.508 -0.9398)
			(stroke
				(width 0.1524)
				(type default)
			)
			(layer "F.SilkS")
		)
		(fp_line
			(start -0.508 -0.9398)
			(end -0.508 0.9398)
			(stroke
				(width 0.1524)
				(type default)
			)
			(layer "F.SilkS")
		)
		(fp_rect
			(start -0.508 0.9398)
			(end 0.508 -0.9398)
			(stroke
				(width 0)
				(type default)
			)
			(fill no)
			(layer "F.CrtYd")
		)
		(fp_rect
			(start -0.508 0.9398)
			(end 0.508 -0.9398)
			(stroke
				(width 0)
				(type default)
			)
			(fill no)
			(layer "F.Fab")
		)
		(pad "1" smd custom
			(at 0 -0.4445 180)
			(size 0.1397 0.1397)
			(layers "F.Cu" "F.Mask" "F.Paste")
			(net "P12VU")
			(options
				(clearance outline)
				(anchor circle)
			)
			(primitives
				(gr_poly
					(pts
						(arc
							(start -0.1778 -0.2794)
							(mid -0.249642 -0.249642)
							(end -0.2794 -0.1778)
						)
						(arc
							(start -0.2794 0.1778)
							(mid -0.249642 0.249642)
							(end -0.1778 0.2794)
						)
						(arc
							(start 0.1778 0.2794)
							(mid 0.249642 0.249642)
							(end 0.2794 0.1778)
						)
						(arc
							(start 0.2794 -0.1778)
							(mid 0.249642 -0.249642)
							(end 0.1778 -0.2794)
						)
					)
					(width 0)
					(fill yes)
				)
			)
		)
		(pad "2" smd custom
			(at 0 0.4445 180)
			(size 0.1397 0.1397)
			(layers "F.Cu" "F.Mask" "F.Paste")
			(net "NCT7904_VSEN7")
			(options
				(clearance outline)
				(anchor circle)
			)
			(primitives
				(gr_poly
					(pts
						(arc
							(start -0.1778 -0.2794)
							(mid -0.249642 -0.249642)
							(end -0.2794 -0.1778)
						)
						(arc
							(start -0.2794 0.1778)
							(mid -0.249642 0.249642)
							(end -0.1778 0.2794)
						)
						(arc
							(start 0.1778 0.2794)
							(mid 0.249642 0.249642)
							(end 0.2794 0.1778)
						)
						(arc
							(start 0.2794 -0.1778)
							(mid 0.249642 -0.249642)
							(end 0.1778 -0.2794)
						)
					)
					(width 0)
					(fill yes)
				)
			)
		)
	)
	(footprint ""
		(layer "F.Cu")
		(at 36.7284 -478.4598 90)
		(property "Reference" "C49"
			(at 0 0 90)
			(layer "F.SilkS")
			(hide yes)
			(effects
				(font
					(size 1.27 1.27)
				)
			)
		)
		(property "Value" "SCD1U50V3KX-GP"
			(at 0 -2.8194 90)
			(unlocked yes)
			(layer "F.Fab")
			(hide yes)
			(effects
				(font
					(size 1.016 1.016)
					(thickness 0.1524)
				)
			)
		)
		(property "Device Type" "C603H36"
			(at 0 -4.3434 90)
			(unlocked yes)
			(layer "F.Fab")
			(hide yes)
			(effects
				(font
					(size 1.016 1.016)
					(thickness 0.1524)
				)
			)
		)
		(duplicate_pad_numbers_are_jumpers no)
		(fp_line
			(start 0.508 0)
			(end -0.508 0)
			(stroke
				(width 0.2032)
				(type default)
			)
			(layer "F.SilkS")
		)
		(fp_rect
			(start -0.5842 1.3335)
			(end 0.5842 -1.3335)
			(stroke
				(width 0)
				(type default)
			)
			(fill no)
			(layer "F.CrtYd")
		)
		(fp_rect
			(start -0.5842 1.3335)
			(end 0.5842 -1.3335)
			(stroke
				(width 0)
				(type default)
			)
			(fill no)
			(layer "F.Fab")
		)
		(pad "1" smd custom
			(at 0 -0.762 90)
			(size 0.2159 0.2159)
			(layers "F.Cu" "F.Mask" "F.Paste")
			(net "P12V")
			(options
				(clearance outline)
				(anchor circle)
			)
			(primitives
				(gr_poly
					(pts
						(arc
							(start -0.3302 -0.4318)
							(mid -0.402042 -0.402042)
							(end -0.4318 -0.3302)
						)
						(arc
							(start -0.4318 0.3302)
							(mid -0.402042 0.402042)
							(end -0.3302 0.4318)
						)
						(arc
							(start 0.3302 0.4318)
							(mid 0.402042 0.402042)
							(end 0.4318 0.3302)
						)
						(arc
							(start 0.4318 -0.3302)
							(mid 0.402042 -0.402042)
							(end 0.3302 -0.4318)
						)
					)
					(width 0)
					(fill yes)
				)
			)
		)
		(pad "2" smd custom
			(at 0 0.762 90)
			(size 0.2159 0.2159)
			(layers "F.Cu" "F.Mask" "F.Paste")
			(net "GND")
			(options
				(clearance outline)
				(anchor circle)
			)
			(primitives
				(gr_poly
					(pts
						(arc
							(start -0.3302 -0.4318)
							(mid -0.402042 -0.402042)
							(end -0.4318 -0.3302)
						)
						(arc
							(start -0.4318 0.3302)
							(mid -0.402042 0.402042)
							(end -0.3302 0.4318)
						)
						(arc
							(start 0.3302 0.4318)
							(mid 0.402042 0.402042)
							(end 0.4318 0.3302)
						)
						(arc
							(start 0.4318 -0.3302)
							(mid 0.402042 -0.402042)
							(end 0.3302 -0.4318)
						)
					)
					(width 0)
					(fill yes)
				)
			)
		)
	)
)
